FILE_TYPE = CONNECTIVITY;
{Allegro Design Entry HDL 16.6-p007 (v16-6-112F) 10/10/2012}
"PAGE_NUMBER" = 183;
0"NC";
1"GND\g";
2"P3V3_STBY\g";
3"P3V3_STBY\g";
4"GND\g";
5"GND\g";
6"GND\g";
7"GND\g";
8"P3V3_STBY\g";
9"GND\g";
10"P3V3_STBY\g";
11"P3V3_STBY\g";
12"GND\g";
13"FM_UART_ALERT_N";
14"UART_BMC_TXD5";
15"SP1_BMC_HOST_UART_TX";
16"TP_PI7C9X1172_SO";
17"TP_GPIO0_DSRB_N";
18"TP_GPIO1_DTRB_N";
19"TP_GPIO2_CDB_N";
20"TP_GPIO3_RIB_N";
21"TP_GPIO4_DSRA_N";
22"TP_GPIO5_DTRA_N";
23"TP_GPIO6_CDA_N";
24"TP_GPIO7_RIA_N";
25"UART_BRIDGE_TXD5";
26"NC_PI7C9X1172_8";
27"TP_PI7C9X1172_RTSA_N";
28"TP_PI7C9X1172_RTSB_N";
29"NC_PI7C9X1172_1";
30"SP1_HOST_BRIDGE_UART_TX";
31"TP_PI7C9X1172_ENIR_N";
32"TP_PI7C9X1172_EN485_N";
33"XTAL_24MHZ_OUT_R";
34"XTAL_24MHZ_IN_R";
35"XTAL_24MHZ_PI7C9X1172_OUT";
36"PWRGD_DSW_PWROK";
37"XTAL_24MHZ_PI7C9X1172_IN";
38"SP1_HOST_BRIDGE_UART_RX";
39"UART_BRIDGE_RXD5";
40"FM_PI7C9X1172_A1";
41"FM_PI7C9X1172_A0";
42"PU_PI7C9X1172_I2C_SPI_N";
43"SMB_SLOTX24_PCH_STBY_LVC3_SDA";
44"SMB_SLOTX24_PCH_STBY_LVC3_SCL";
45"UART_BMC_RXD5";
46"SP1_BMC_HOST_UART_RX";
%"PI7C9X1172"
"1","(1475,1025)","0","mstr_controller","I1";
;
CDS_LIB"mstr_controller"
BOM_COST"LBG_UART"
CDS_SEC"1"
$SEC"1"
CDS_LOCATION"EU9F3"
ROOM"LBG"
PACK_TYPE"QFN"
PART_NUMBER"H66899-001"
MATERIAL"IC"
LOCATION"EU9F3";
"VDD"
$PN"29"11;
"XTAL2"
$PN"10"33;
"XTAL1"
$PN"9"34;
"GND"
$PN"12"1;
"THPAD"
$PN"33"1;
"IRQ_N"
$PN"20"13;
"NC<0>"
$PN"1"29;
"NC<1>"
$PN"8"26;
"RTSB_N"
$PN"15"28;
"RTSA_N"
$PN"21"27;
"TXB"
$PN"7"25;
"TXA"
$PN"6"30;
"GPIO7_RIA_N"
$PN"28"24;
"GPIO3_RIB_N"
$PN"14"20;
"GPIO6_CDA_N"
$PN"27"23;
"GPIO4_DSRA_N"
$PN"26"21;
"GPIO5_DTRA_N"
$PN"22"22;
"GPIO2_CDB_N"
$PN"11"19;
"GPIO1_DTRB_N"
$PN"23"18;
"GPIO0_DSRB_N"
$PN"13"17;
"SO"
$PN"2"16;
"CTSA_N"
$PN"25"9;
"CTSB_N"
$PN"16"9;
"RXA"
$PN"5"38;
"RXB"
$PN"4"39;
"ENIR_N"
$PN"18"31;
"EN485_N"
$PN"19"32;
"RESET_N"
$PN"24"36;
"I2C_SPI_N"
$PN"32"42;
"A0_CS_N"
$PN"30"41;
"A1_S1"
$PN"31"40;
"SCL"
$PN"17"44;
"SDA"
$PN"3"43;
%"GND"
"1","(2250,25)","0","mstr_symbols","I10";
;
HDL_POWER"GND"
CDS_LIB"mstr_symbols"
SIZE"1B"
VOLTAGE"0.0V"
BODY_TYPE"PLUMBING";
"A\NAC"1;
%"RES"
"2","(-1150,600)","0","mstr_discrete","I11";
;
ROOM"LBG"
$SEC"1"
CDS_SEC"1"
BOM_COST"LBG_UART"
CDS_LOCATION"R9F50"
CDS_LIB"mstr_discrete"
LOCATION"R9F50"
PART_NUMBER"G21796-026"
VALUE"1.00K"
PACK_TYPE"0402"
MATERIAL"CHIP"
WATTAGE"1/16W"
TOLERANCE"1%";
"A"
$PN"1"40;
"B"
$PN"2"5;
%"RES"
"2","(-1500,600)","0","mstr_discrete","I12";
;
ROOM"LBG"
$SEC"1"
CDS_SEC"1"
BOM_COST"LBG_UART"
CDS_LIB"mstr_discrete"
CDS_LOCATION"R9F51"
MATERIAL"CHIP"
TOLERANCE"1%"
VALUE"1.00K"
LOCATION"R9F51"
WATTAGE"1/16W"
PART_NUMBER"G21796-026"
PACK_TYPE"0402";
"A"
$PN"1"41;
"B"
$PN"2"4;
%"RES"
"2","(-1150,1050)","0","mstr_discrete","I13";
;
CDS_SEC"1"
SEC"1"
SEC_TYPE"0402"
BOM_COST"LBG_UART"
ROOM"LBG"
CDS_LOCATION"R9F48"
CDS_LIB"mstr_discrete"
MATERIAL"EMPTY"
LOCATION"R9F48"
PART_NUMBER"G21796-072"
VALUE"4.75K"
PACK_TYPE"0402"
WATTAGE"1/16W"
TOLERANCE"1%";
"A"
$PN"1"3;
"B"
$PN"2"40;
%"RES"
"2","(-1500,1050)","0","mstr_discrete","I14";
;
CDS_SEC"1"
SEC"1"
SEC_TYPE"0402"
BOM_COST"LBG_UART"
ROOM"LBG"
CDS_LOCATION"R9F49"
CDS_LIB"mstr_discrete"
LOCATION"R9F49"
VALUE"4.75K"
TOLERANCE"1%"
WATTAGE"1/16W"
PART_NUMBER"G21796-072"
MATERIAL"EMPTY"
PACK_TYPE"0402";
"A"
$PN"1"2;
"B"
$PN"2"41;
%"P3V3_STBY"
"1","(-1500,1300)","0","mstr_symbols","I15";
;
CDS_LIB"mstr_symbols"
SIZE"1B"
VOLTAGE"3.3V"
BODY_TYPE"PLUMBING"
HDL_POWER"P3V3_STBY";
"G\NAC"2;
%"P3V3_STBY"
"1","(-1150,1300)","0","mstr_symbols","I16";
;
CDS_LIB"mstr_symbols"
SIZE"1B"
VOLTAGE"3.3V"
BODY_TYPE"PLUMBING"
HDL_POWER"P3V3_STBY";
"G\NAC"3;
%"GND"
"1","(-1500,325)","0","mstr_symbols","I17";
;
HDL_POWER"GND"
SIZE"1B"
CDS_LIB"mstr_symbols"
VOLTAGE"0.0V"
BODY_TYPE"PLUMBING";
"A\NAC"4;
%"GND"
"1","(-1150,325)","0","mstr_symbols","I18";
;
HDL_POWER"GND"
SIZE"1B"
CDS_LIB"mstr_symbols"
VOLTAGE"0.0V"
BODY_TYPE"PLUMBING";
"A\NAC"5;
%"CRYSTAL"
"1","(-225,50)","0","mstr_discrete","I19";
;
CDS_SEC"1"
BOM_COST"LBG_UART"
CDS_LIB"mstr_discrete"
SEC_TYPE"SM"
SEC"1"
CDS_LOCATION"Y9F1"
ROOM"LBG"
PART_NUMBER"D95126-001"
PACK_TYPE"SM"
LOCATION"Y9F1"
VALUE"24.000MHZ"
MATERIAL"IC";
"B"
$PN"2"35;
"A"
$PN"1"37;
%"CAP"
"1","(-475,-200)","0","mstr_discrete","I20";
;
$SEC"1"
CDS_SEC"1"
BOM_COST"LBG_UART"
ROOM"LBG"
CDS_LOCATION"C9F20"
CDS_LIB"mstr_discrete"
PART_NUMBER"A36095-043"
VALUE"12.0PF"
PACK_TYPE"0402LF"
LOCATION"C9F20"
TOLERANCE"5%"
VOLTAGE"50V"
MATERIAL"COG";
"A"
$PN"1"37;
"B"
$PN"2"7;
%"CAP"
"1","(25,-200)","0","mstr_discrete","I21";
;
$SEC"1"
CDS_SEC"1"
BOM_COST"LBG_UART"
ROOM"LBG"
CDS_LOCATION"C9F21"
CDS_LIB"mstr_discrete"
PART_NUMBER"A36095-043"
LOCATION"C9F21"
VALUE"12.0PF"
TOLERANCE"5%"
VOLTAGE"50V"
MATERIAL"COG"
PACK_TYPE"0402LF";
"A"
$PN"1"35;
"B"
$PN"2"6;
%"GND"
"1","(25,-425)","0","mstr_symbols","I22";
;
HDL_POWER"GND"
SIZE"1B"
CDS_LIB"mstr_symbols"
VOLTAGE"0.0V"
BODY_TYPE"PLUMBING";
"A\NAC"6;
%"GND"
"1","(-475,-425)","0","mstr_symbols","I23";
;
HDL_POWER"GND"
CDS_LIB"mstr_symbols"
SIZE"1B"
VOLTAGE"0.0V"
BODY_TYPE"PLUMBING";
"A\NAC"7;
%"RES"
"1","(125,575)","0","mstr_discrete","I24";
;
CDS_SEC"1"
SEC"1"
SEC_TYPE"0402"
ROOM"LBG"
BOM_COST"LBG_UART"
CDS_LOCATION"R9F58"
CDS_LIB"mstr_discrete"
MATERIAL"CHIP"
TOLERANCE"5%"
LOCATION"R9F58"
VALUE"0.0"
PACK_TYPE"0402"
PART_NUMBER"G21497-005"
WATTAGE"1/16W";
"B"
$PN"2"34;
"A"
$PN"1"37;
%"RES"
"1","(275,325)","0","mstr_discrete","I25";
;
CDS_SEC"1"
SEC_TYPE"0402"
SEC"1"
CDS_LIB"mstr_discrete"
BOM_COST"LBG_UART"
CDS_LOCATION"R9F59"
ROOM"LBG"
PACK_TYPE"0402"
MATERIAL"CHIP"
TOLERANCE"5%"
PART_NUMBER"G21497-005"
LOCATION"R9F59"
VALUE"0.0"
WATTAGE"1/16W";
"B"
$PN"2"33;
"A"
$PN"1"35;
%"RES"
"2","(3700,700)","0","mstr_discrete","I30";
;
CDS_SEC"1"
SEC_TYPE"0402"
SEC"1"
CDS_LOCATION"R9F55"
BOM_COST"LBG_UART"
ROOM"LBG"
CDS_LIB"mstr_discrete"
LOCATION"R9F55"
PART_NUMBER"G21796-072"
VALUE"4.75K"
PACK_TYPE"0402"
MATERIAL"CHIP"
WATTAGE"1/16W"
TOLERANCE"1%";
"A"
$PN"1"8;
"B"
$PN"2"13;
%"P3V3_STBY"
"1","(3700,900)","0","mstr_symbols","I31";
;
SIZE"1B"
CDS_LIB"mstr_symbols"
BODY_TYPE"PLUMBING"
VOLTAGE"3.3V"
HDL_POWER"P3V3_STBY";
"G\NAC"8;
%"GND"
"1","(675,1325)","0","mstr_symbols","I32";
;
HDL_POWER"GND"
CDS_LIB"mstr_symbols"
VOLTAGE"0.0V"
BODY_TYPE"PLUMBING"
SIZE"1B";
"A\NAC"9;
%"RES"
"1","(-150,1025)","0","mstr_discrete","I4";
;
CDS_SEC"1"
PACK_TYPE"0402"
ROOM"LBG"
BOM_COST"LBG_UART"
CDS_LIB"mstr_discrete"
SEC"1"
CDS_LOCATION"R9F47"
SEC_TYPE"0402"
MATERIAL"CHIP"
PART_NUMBER"G21796-072"
LOCATION"R9F47"
TOLERANCE"1%"
VALUE"4.75K"
WATTAGE"1/16W";
"B"
$PN"2"42;
"A"
$PN"1"10;
%"RES"
"1","(3950,1225)","0","mstr_discrete","I48";
;
CDS_SEC"1"
SEC_TYPE"0402"
BOM_COST"LBG_UART"
SEC"1"
ROOM"LBG"
CDS_LIB"mstr_discrete"
CDS_LOCATION"R9F57"
PACK_TYPE"0402"
PART_NUMBER"G21497-005"
MATERIAL"CHIP"
TOLERANCE"5%"
WATTAGE"1/16W"
LOCATION"R9F57"
VALUE"0.0";
"B"
$PN"2"14;
"A"
$PN"1"25;
%"RES"
"1","(3475,1275)","0","mstr_discrete","I49";
;
CDS_SEC"1"
SEC_TYPE"0402"
BOM_COST"LBG_UART"
SEC"1"
ROOM"LBG"
CDS_LIB"mstr_discrete"
CDS_LOCATION"R9F56"
PART_NUMBER"G21497-005"
PACK_TYPE"0402"
MATERIAL"CHIP"
VALUE"0.0"
TOLERANCE"5%"
LOCATION"R9F56"
WATTAGE"1/16W";
"B"
$PN"2"15;
"A"
$PN"1"30;
%"P3V3_STBY"
"1","(-475,1150)","0","mstr_symbols","I5";
;
SIZE"1B"
CDS_LIB"mstr_symbols"
VOLTAGE"3.3V"
BODY_TYPE"PLUMBING"
HDL_POWER"P3V3_STBY";
"G\NAC"10;
%"RES"
"1","(-750,1500)","0","mstr_discrete","I52";
;
CDS_SEC"1"
SEC_TYPE"0402"
SEC"1"
BOM_COST"LBG_UART"
ROOM"LBG"
CDS_LIB"mstr_discrete"
CDS_LOCATION"R9F54"
PART_NUMBER"G21497-005"
PACK_TYPE"0402"
MATERIAL"CHIP"
TOLERANCE"5%"
VALUE"0.0"
LOCATION"R9F54"
WATTAGE"1/16W";
"B"
$PN"2"38;
"A"
$PN"1"46;
%"RES"
"1","(-275,1450)","0","mstr_discrete","I53";
;
CDS_SEC"1"
SEC"1"
BOM_COST"LBG_UART"
SEC_TYPE"0402"
ROOM"LBG"
CDS_LIB"mstr_discrete"
CDS_LOCATION"R9F53"
PACK_TYPE"0402"
TOLERANCE"5%"
MATERIAL"CHIP"
LOCATION"R9F53"
VALUE"0.0"
PART_NUMBER"G21497-005"
WATTAGE"1/16W";
"B"
$PN"2"39;
"A"
$PN"1"45;
%"P3V3_STBY"
"1","(550,2050)","0","mstr_symbols","I6";
;
CDS_LIB"mstr_symbols"
SIZE"1B"
VOLTAGE"3.3V"
BODY_TYPE"PLUMBING"
HDL_POWER"P3V3_STBY";
"G\NAC"11;
%"CAP_A"
"1","(325,1775)","0","dev_discrete","I7";
;
BOM_COST"LBG_UART"
CDS_LOCATION"C9F19"
ROOM"LBG"
CDS_SEC"1"
SEC"1"
SEC_TYPE"0402V"
CDS_LIB"dev_discrete"
LOCATION"C9F19"
PART_NUMBER"A36096-030"
VALUE"0.1UF"
PACK_TYPE"0402V"
VOLTAGE"16V"
TOLERANCE"10%"
MATERIAL"X7R";
"B"
$PN"2"12;
"A"
$PN"1"11;
%"GND"
"1","(325,1575)","0","mstr_symbols","I8";
;
HDL_POWER"GND"
CDS_LIB"mstr_symbols"
VOLTAGE"0.0V"
BODY_TYPE"PLUMBING"
SIZE"1B";
"A\NAC"12;
END.
